(kicad_pcb
	(version 20260206)
	(generator "pcbnew")
	(generator_version "10.0")
	(general
		(thickness 1.6)
		(legacy_teardrops no)
	)
	(paper "A4")
	(title_block
		(title "9054_F0T_PDB_BD_GPU_F_V04_1213_1550_OCP.brd")
		(comment 1 "Grand Teton / footprints 381-385 of 608")
	)
	(layers
		(0 "F.Cu" signal "TOP")
		(4 "In1.Cu" signal "GND")
		(6 "In2.Cu" signal "IN1")
		(8 "In3.Cu" signal "GND1")
		(10 "In4.Cu" signal "VCC")
		(12 "In5.Cu" signal "VCC1")
		(14 "In6.Cu" signal "GND2")
		(16 "In7.Cu" signal "IN2")
		(18 "In8.Cu" signal "GND3")
		(2 "B.Cu" signal "BOTTOM")
		(9 "F.Adhes" user "F.Adhesive")
		(11 "B.Adhes" user "B.Adhesive")
		(13 "F.Paste" user "Package Geometry/Pastemask Top")
		(15 "B.Paste" user "Package Geometry/Pastemask Bottom")
		(5 "F.SilkS" user "Ref Des/Silkscreen Top")
		(7 "B.SilkS" user "Ref Des/Silkscreen Bottom")
		(1 "F.Mask" user "Board Geometry/Soldermask Top")
		(3 "B.Mask" user "Board Geometry/Soldermask Bottom")
		(17 "Dwgs.User" user "User.Drawings")
		(19 "Cmts.User" user "User.Comments")
		(21 "Eco1.User" user "User.Eco1")
		(23 "Eco2.User" user "User.Eco2")
		(25 "Edge.Cuts" user "Board Geometry/Outline")
		(27 "Margin" user)
		(31 "F.CrtYd" user "Package Geometry/Place Bound Top")
		(29 "B.CrtYd" user "Package Geometry/Place Bound Bottom")
		(35 "F.Fab" user "Ref Des/Assembly Top")
		(33 "B.Fab" user "Ref Des/Assembly Bottom")
	)
	(footprint ""
		(layer "F.Cu")
		(at 414.02 -42.545 180)
		(property "Reference" "R5927"
			(at 0 0 180)
			(layer "F.SilkS")
			(hide yes)
			(effects
				(font
					(size 1.27 1.27)
				)
			)
		)
		(property "Value" ""
			(at 0 0 180)
			(layer "F.Fab")
			(effects
				(font
					(size 1.27 1.27)
				)
			)
		)
		(duplicate_pad_numbers_are_jumpers no)
		(fp_line
			(start 0.7874 0.4064)
			(end -0.7874 0.4064)
			(stroke
				(width 0.1524)
				(type default)
			)
			(layer "F.SilkS")
		)
		(fp_line
			(start 0.7874 -0.4064)
			(end 0.7874 0.4064)
			(stroke
				(width 0.1524)
				(type default)
			)
			(layer "F.SilkS")
		)
		(fp_line
			(start -0.7874 0.4064)
			(end -0.7874 -0.4064)
			(stroke
				(width 0.1524)
				(type default)
			)
			(layer "F.SilkS")
		)
		(fp_line
			(start -0.7874 -0.4064)
			(end 0.7874 -0.4064)
			(stroke
				(width 0.1524)
				(type default)
			)
			(layer "F.SilkS")
		)
		(fp_line
			(start 0.67945 0.3048)
			(end 0.120396 0.3048)
			(stroke
				(width 0.1)
				(type default)
			)
			(layer "F.Fab")
		)
		(fp_line
			(start 0.67945 -0.3048)
			(end 0.67945 0.3048)
			(stroke
				(width 0.1)
				(type default)
			)
			(layer "F.Fab")
		)
		(fp_line
			(start 0.12065 -0.2794)
			(end 0.12065 -0.3048)
			(stroke
				(width 0.1)
				(type default)
			)
			(layer "F.Fab")
		)
		(fp_line
			(start 0.12065 -0.3048)
			(end 0.67945 -0.3048)
			(stroke
				(width 0.1)
				(type default)
			)
			(layer "F.Fab")
		)
		(fp_line
			(start 0.120396 0.3048)
			(end 0.120396 0.2794)
			(stroke
				(width 0.1)
				(type default)
			)
			(layer "F.Fab")
		)
		(fp_line
			(start 0.120396 0.2794)
			(end -0.12065 0.2794)
			(stroke
				(width 0.1)
				(type default)
			)
			(layer "F.Fab")
		)
		(fp_line
			(start -0.12065 0.3048)
			(end -0.67945 0.3048)
			(stroke
				(width 0.1)
				(type default)
			)
			(layer "F.Fab")
		)
		(fp_line
			(start -0.12065 0.2794)
			(end -0.12065 0.3048)
			(stroke
				(width 0.1)
				(type default)
			)
			(layer "F.Fab")
		)
		(fp_line
			(start -0.12065 -0.2794)
			(end 0.12065 -0.2794)
			(stroke
				(width 0.1)
				(type default)
			)
			(layer "F.Fab")
		)
		(fp_line
			(start -0.12065 -0.305054)
			(end -0.12065 -0.2794)
			(stroke
				(width 0.1)
				(type default)
			)
			(layer "F.Fab")
		)
		(fp_line
			(start -0.67945 0.3048)
			(end -0.67945 -0.305054)
			(stroke
				(width 0.1)
				(type default)
			)
			(layer "F.Fab")
		)
		(fp_line
			(start -0.67945 -0.305054)
			(end -0.12065 -0.305054)
			(stroke
				(width 0.1)
				(type default)
			)
			(layer "F.Fab")
		)
		(pad "1" smd circle
			(at -0.40005 0 180)
			(size 0 0)
			(layers "F.Cu" "F.Mask" "F.Paste")
			(net "PRSNT_FAN_BP0_N")
		)
		(pad "2" smd circle
			(at 0.40005 0 180)
			(size 0 0)
			(layers "F.Cu" "F.Mask" "F.Paste")
			(net "PRSNT_FAN_BP0_R_N")
		)
	)
	(footprint ""
		(layer "F.Cu")
		(at 378.517912 -17.907254 -90)
		(property "Reference" "R73"
			(at 0 0 270)
			(layer "F.SilkS")
			(hide yes)
			(effects
				(font
					(size 1.27 1.27)
				)
			)
		)
		(property "Value" ""
			(at 0 0 270)
			(layer "F.Fab")
			(effects
				(font
					(size 1.27 1.27)
				)
			)
		)
		(duplicate_pad_numbers_are_jumpers no)
		(fp_line
			(start -0.7874 0.4064)
			(end -0.7874 -0.4064)
			(stroke
				(width 0.1524)
				(type default)
			)
			(layer "F.SilkS")
		)
		(fp_line
			(start 0.7874 0.4064)
			(end -0.7874 0.4064)
			(stroke
				(width 0.1524)
				(type default)
			)
			(layer "F.SilkS")
		)
		(fp_line
			(start -0.7874 -0.4064)
			(end 0.7874 -0.4064)
			(stroke
				(width 0.1524)
				(type default)
			)
			(layer "F.SilkS")
		)
		(fp_line
			(start 0.7874 -0.4064)
			(end 0.7874 0.4064)
			(stroke
				(width 0.1524)
				(type default)
			)
			(layer "F.SilkS")
		)
		(fp_line
			(start -0.67945 0.3048)
			(end -0.67945 -0.305054)
			(stroke
				(width 0.1)
				(type default)
			)
			(layer "F.Fab")
		)
		(fp_line
			(start -0.12065 0.3048)
			(end -0.67945 0.3048)
			(stroke
				(width 0.1)
				(type default)
			)
			(layer "F.Fab")
		)
		(fp_line
			(start 0.120396 0.3048)
			(end 0.120396 0.2794)
			(stroke
				(width 0.1)
				(type default)
			)
			(layer "F.Fab")
		)
		(fp_line
			(start 0.67945 0.3048)
			(end 0.120396 0.3048)
			(stroke
				(width 0.1)
				(type default)
			)
			(layer "F.Fab")
		)
		(fp_line
			(start -0.12065 0.2794)
			(end -0.12065 0.3048)
			(stroke
				(width 0.1)
				(type default)
			)
			(layer "F.Fab")
		)
		(fp_line
			(start 0.120396 0.2794)
			(end -0.12065 0.2794)
			(stroke
				(width 0.1)
				(type default)
			)
			(layer "F.Fab")
		)
		(fp_line
			(start -0.12065 -0.2794)
			(end 0.12065 -0.2794)
			(stroke
				(width 0.1)
				(type default)
			)
			(layer "F.Fab")
		)
		(fp_line
			(start 0.12065 -0.2794)
			(end 0.12065 -0.3048)
			(stroke
				(width 0.1)
				(type default)
			)
			(layer "F.Fab")
		)
		(fp_line
			(start 0.12065 -0.3048)
			(end 0.67945 -0.3048)
			(stroke
				(width 0.1)
				(type default)
			)
			(layer "F.Fab")
		)
		(fp_line
			(start 0.67945 -0.3048)
			(end 0.67945 0.3048)
			(stroke
				(width 0.1)
				(type default)
			)
			(layer "F.Fab")
		)
		(fp_line
			(start -0.67945 -0.305054)
			(end -0.12065 -0.305054)
			(stroke
				(width 0.1)
				(type default)
			)
			(layer "F.Fab")
		)
		(fp_line
			(start -0.12065 -0.305054)
			(end -0.12065 -0.2794)
			(stroke
				(width 0.1)
				(type default)
			)
			(layer "F.Fab")
		)
		(pad "1" smd circle
			(at -0.40005 0 270)
			(size 0 0)
			(layers "F.Cu" "F.Mask" "F.Paste")
			(net "SMB_PDB_FAN_0_SDA")
		)
		(pad "2" smd circle
			(at 0.40005 0 270)
			(size 0 0)
			(layers "F.Cu" "F.Mask" "F.Paste")
			(net "SMB_PDB_FAN_0_R_SDA")
		)
	)
	(footprint ""
		(layer "F.Cu")
		(at 449.3514 -93.98)
		(property "Reference" "PC58"
			(at 0 0 0)
			(layer "F.SilkS")
			(hide yes)
			(effects
				(font
					(size 1.27 1.27)
				)
			)
		)
		(property "Value" ""
			(at 0 0 0)
			(layer "F.Fab")
			(effects
				(font
					(size 1.27 1.27)
				)
			)
		)
		(duplicate_pad_numbers_are_jumpers no)
		(fp_line
			(start -1.524 -0.762)
			(end 1.524 -0.762)
			(stroke
				(width 0.1524)
				(type default)
			)
			(layer "F.SilkS")
		)
		(fp_line
			(start -1.524 0.762)
			(end -1.524 -0.762)
			(stroke
				(width 0.1524)
				(type default)
			)
			(layer "F.SilkS")
		)
		(fp_line
			(start 1.524 -0.762)
			(end 1.524 0.762)
			(stroke
				(width 0.1524)
				(type default)
			)
			(layer "F.SilkS")
		)
		(fp_line
			(start 1.524 0.762)
			(end -1.524 0.762)
			(stroke
				(width 0.1524)
				(type default)
			)
			(layer "F.SilkS")
		)
		(fp_line
			(start -1.1049 -0.724916)
			(end -1.1049 0.724916)
			(stroke
				(width 0.1)
				(type default)
			)
			(layer "F.Fab")
		)
		(fp_line
			(start -1.1049 0.724916)
			(end 1.1049 0.724916)
			(stroke
				(width 0.1)
				(type default)
			)
			(layer "F.Fab")
		)
		(fp_line
			(start 1.1049 -0.724916)
			(end -1.1049 -0.724916)
			(stroke
				(width 0.1)
				(type default)
			)
			(layer "F.Fab")
		)
		(fp_line
			(start 1.1049 0.724916)
			(end 1.1049 -0.724916)
			(stroke
				(width 0.1)
				(type default)
			)
			(layer "F.Fab")
		)
		(pad "1" smd rect
			(at -0.889 0 180)
			(size 1.016 1.27)
			(layers "F.Cu" "F.Mask" "F.Paste")
			(net "SW_P3V3_HPDB_FLT")
		)
		(pad "2" smd rect
			(at 0.889 0 180)
			(size 1.016 1.27)
			(layers "F.Cu" "F.Mask" "F.Paste")
			(net "GND")
		)
	)
	(footprint ""
		(layer "F.Cu")
		(at 378.079 -78.74)
		(property "Reference" "PC40"
			(at 5.1054 -4.79933 0)
			(unlocked yes)
			(layer "F.SilkS")
			(effects
				(font
					(size 0.7874 0.5842)
					(thickness 0.1524)
				)
				(justify left)
			)
		)
		(property "Value" ""
			(at 0 0 0)
			(layer "F.Fab")
			(effects
				(font
					(size 1.27 1.27)
				)
			)
		)
		(duplicate_pad_numbers_are_jumpers no)
		(fp_line
			(start -9.253728 3.750056)
			(end 9.249918 3.750056)
			(stroke
				(width 0.1524)
				(type default)
			)
			(layer "F.SilkS")
		)
		(fp_line
			(start 0 3.750056)
			(end -9.253728 3.750056)
			(stroke
				(width 0.1524)
				(type default)
			)
			(layer "F.SilkS")
		)
		(fp_circle
			(center 0 3.750056)
			(end 9.249918 3.750056)
			(stroke
				(width 0.1524)
				(type default)
			)
			(fill no)
			(layer "F.SilkS")
		)
		(fp_poly
			(pts
				(arc
					(start 9.249918 3.750056)
					(mid 0 12.999974)
					(end -9.249918 3.750056)
				)
			)
			(stroke
				(width 0)
				(type default)
			)
			(fill yes)
			(layer "F.SilkS")
		)
		(fp_circle
			(center 0 3.750056)
			(end 9.249918 3.750056)
			(stroke
				(width 0.1)
				(type default)
			)
			(fill no)
			(layer "F.Fab")
		)
		(pad "1" thru_hole rect
			(at 0 0)
			(size 1.778 1.778)
			(drill 1.27)
			(layers "*.Cu" "*.Mask")
			(remove_unused_layers no)
			(net "P52V_HS1")
			(clearance 0)
			(padstack
				(mode front_inner_back)
				(layer "Inner"
					(shape circle)
					(size 1.778 1.778)
					(clearance 0)
				)
				(layer "B.Cu"
					(shape rect)
					(size 1.778 1.778)
					(clearance 0)
				)
			)
		)
		(pad "2" thru_hole circle
			(at 0 7.500112)
			(size 1.778 1.778)
			(drill 1.27)
			(layers "*.Cu" "*.Mask")
			(remove_unused_layers no)
			(net "GND")
			(clearance 0)
		)
	)
	(footprint ""
		(layer "F.Cu")
		(at 25.183846 -153.440892)
		(property "Reference" ""
			(at 0 0 0)
			(layer "F.SilkS")
			(hide yes)
			(effects
				(font
					(size 1.27 1.27)
				)
			)
		)
		(property "Value" ""
			(at 0 0 0)
			(layer "F.Fab")
			(effects
				(font
					(size 1.27 1.27)
				)
			)
		)
		(duplicate_pad_numbers_are_jumpers no)
		(pad "1" smd circle
			(at 0 0)
			(size 0.9906 0.9906)
			(layers "F.Cu" "F.Mask" "F.Paste")
			(net "Net_245")
		)
		(zone
			(layer "F.Cu")
			(hatch none 0.5)
			(connect_pads
				(clearance 0)
			)
			(min_thickness 0.25)
			(keepout
				(tracks not_allowed)
				(vias allowed)
				(pads allowed)
				(copperpour not_allowed)
				(footprints allowed)
			)
			(placement
				(enabled no)
				(sheetname "")
			)
			(fill
				(thermal_gap 0.5)
				(thermal_bridge_width 0.5)
				(island_removal_mode 0)
			)
			(polygon
				(pts
					(arc
						(start 26.809446 -153.440892)
						(mid 23.558246 -153.440892)
						(end 26.809446 -153.440892)
					)
				)
			)
		)
	)
)
